-- pcdb file, Rev:1.0 written by Allegro Design Entry HDL 16.5-S008 (v16-5-13Y) 10/18/2011 on Tue Oct 25 14:31:39 2011
#ISCELL
  mstr_standard drawing *
  *
#ISCELL
  mstr_standard synonym *
  page1_4p
